(kicad_pcb
	(version 20260206)
	(generator "pcbnew")
	(generator_version "10.0")
	(general
		(thickness 1.6)
		(legacy_teardrops no)
	)
	(paper "A4")
	(title_block
		(title "9054_F0T_PDB_BD_GPU_F_V04_1213_1550_OCP.brd")
		(comment 1 "Grand Teton / footprints 228-234 of 608")
	)
	(layers
		(0 "F.Cu" signal "TOP")
		(4 "In1.Cu" signal "GND")
		(6 "In2.Cu" signal "IN1")
		(8 "In3.Cu" signal "GND1")
		(10 "In4.Cu" signal "VCC")
		(12 "In5.Cu" signal "VCC1")
		(14 "In6.Cu" signal "GND2")
		(16 "In7.Cu" signal "IN2")
		(18 "In8.Cu" signal "GND3")
		(2 "B.Cu" signal "BOTTOM")
		(9 "F.Adhes" user "F.Adhesive")
		(11 "B.Adhes" user "B.Adhesive")
		(13 "F.Paste" user "Package Geometry/Pastemask Top")
		(15 "B.Paste" user "Package Geometry/Pastemask Bottom")
		(5 "F.SilkS" user "Ref Des/Silkscreen Top")
		(7 "B.SilkS" user "Ref Des/Silkscreen Bottom")
		(1 "F.Mask" user "Board Geometry/Soldermask Top")
		(3 "B.Mask" user "Board Geometry/Soldermask Bottom")
		(17 "Dwgs.User" user "User.Drawings")
		(19 "Cmts.User" user "User.Comments")
		(21 "Eco1.User" user "User.Eco1")
		(23 "Eco2.User" user "User.Eco2")
		(25 "Edge.Cuts" user "Board Geometry/Outline")
		(27 "Margin" user)
		(31 "F.CrtYd" user "Package Geometry/Place Bound Top")
		(29 "B.CrtYd" user "Package Geometry/Place Bound Bottom")
		(35 "F.Fab" user "Ref Des/Assembly Top")
		(33 "B.Fab" user "Ref Des/Assembly Bottom")
	)
	(footprint ""
		(layer "F.Cu")
		(at 304.616358 -63.373)
		(property "Reference" "PR479"
			(at -3.943858 4.73837 0)
			(unlocked yes)
			(layer "F.SilkS")
			(effects
				(font
					(size 0.7874 0.5842)
					(thickness 0.1524)
				)
				(justify left)
			)
		)
		(property "Value" ""
			(at 0 0 0)
			(layer "F.Fab")
			(effects
				(font
					(size 1.27 1.27)
				)
			)
		)
		(duplicate_pad_numbers_are_jumpers no)
		(fp_line
			(start -3.9878 -3.5814)
			(end 3.9878 -3.5814)
			(stroke
				(width 0.1524)
				(type default)
			)
			(layer "F.SilkS")
		)
		(fp_line
			(start -3.9878 3.5814)
			(end -3.9878 -3.5814)
			(stroke
				(width 0.1524)
				(type default)
			)
			(layer "F.SilkS")
		)
		(fp_line
			(start 3.9878 -3.5814)
			(end 3.9878 3.5814)
			(stroke
				(width 0.1524)
				(type default)
			)
			(layer "F.SilkS")
		)
		(fp_line
			(start 3.9878 3.5814)
			(end -3.9878 3.5814)
			(stroke
				(width 0.1524)
				(type default)
			)
			(layer "F.SilkS")
		)
		(fp_line
			(start -3.5306 -3.353054)
			(end 3.5306 -3.353054)
			(stroke
				(width 0.1)
				(type default)
			)
			(layer "F.Fab")
		)
		(fp_line
			(start -3.5306 3.353054)
			(end -3.5306 -3.353054)
			(stroke
				(width 0.1)
				(type default)
			)
			(layer "F.Fab")
		)
		(fp_line
			(start 3.5306 -3.353054)
			(end 3.5306 3.353054)
			(stroke
				(width 0.1)
				(type default)
			)
			(layer "F.Fab")
		)
		(fp_line
			(start 3.5306 3.353054)
			(end -3.5306 3.353054)
			(stroke
				(width 0.1)
				(type default)
			)
			(layer "F.Fab")
		)
		(pad "1A" smd rect
			(at -2.249932 0 180)
			(size 3.2004 6.858)
			(layers "F.Cu" "F.Mask" "F.Paste")
			(net "P52V_1")
		)
		(pad "1B" smd rect
			(at -0.776732 0)
			(size 0.254 0.508)
			(layers "F.Cu" "F.Mask" "F.Paste")
			(net "P52V_HS1_SENSE_P_R1")
		)
		(pad "2A" smd rect
			(at 2.249932 0 180)
			(size 3.2004 6.858)
			(layers "F.Cu" "F.Mask" "F.Paste")
			(net "P52V_HS1_DRAIN_1")
		)
		(pad "2B" smd rect
			(at 0.776732 0)
			(size 0.254 0.508)
			(layers "F.Cu" "F.Mask" "F.Paste")
			(net "P52V_HS1_SENSE_N_R1")
		)
	)
	(footprint ""
		(layer "F.Cu")
		(at 432.943 -52.832)
		(property "Reference" "R5899"
			(at 0 0 0)
			(layer "F.SilkS")
			(hide yes)
			(effects
				(font
					(size 1.27 1.27)
				)
			)
		)
		(property "Value" ""
			(at 0 0 0)
			(layer "F.Fab")
			(effects
				(font
					(size 1.27 1.27)
				)
			)
		)
		(duplicate_pad_numbers_are_jumpers no)
		(fp_line
			(start -0.7874 -0.4064)
			(end 0.7874 -0.4064)
			(stroke
				(width 0.1524)
				(type default)
			)
			(layer "F.SilkS")
		)
		(fp_line
			(start -0.7874 0.4064)
			(end -0.7874 -0.4064)
			(stroke
				(width 0.1524)
				(type default)
			)
			(layer "F.SilkS")
		)
		(fp_line
			(start 0.7874 -0.4064)
			(end 0.7874 0.4064)
			(stroke
				(width 0.1524)
				(type default)
			)
			(layer "F.SilkS")
		)
		(fp_line
			(start 0.7874 0.4064)
			(end -0.7874 0.4064)
			(stroke
				(width 0.1524)
				(type default)
			)
			(layer "F.SilkS")
		)
		(fp_line
			(start -0.67945 -0.305054)
			(end -0.12065 -0.305054)
			(stroke
				(width 0.1)
				(type default)
			)
			(layer "F.Fab")
		)
		(fp_line
			(start -0.67945 0.3048)
			(end -0.67945 -0.305054)
			(stroke
				(width 0.1)
				(type default)
			)
			(layer "F.Fab")
		)
		(fp_line
			(start -0.12065 -0.305054)
			(end -0.12065 -0.2794)
			(stroke
				(width 0.1)
				(type default)
			)
			(layer "F.Fab")
		)
		(fp_line
			(start -0.12065 -0.2794)
			(end 0.12065 -0.2794)
			(stroke
				(width 0.1)
				(type default)
			)
			(layer "F.Fab")
		)
		(fp_line
			(start -0.12065 0.2794)
			(end -0.12065 0.3048)
			(stroke
				(width 0.1)
				(type default)
			)
			(layer "F.Fab")
		)
		(fp_line
			(start -0.12065 0.3048)
			(end -0.67945 0.3048)
			(stroke
				(width 0.1)
				(type default)
			)
			(layer "F.Fab")
		)
		(fp_line
			(start 0.120396 0.2794)
			(end -0.12065 0.2794)
			(stroke
				(width 0.1)
				(type default)
			)
			(layer "F.Fab")
		)
		(fp_line
			(start 0.120396 0.3048)
			(end 0.120396 0.2794)
			(stroke
				(width 0.1)
				(type default)
			)
			(layer "F.Fab")
		)
		(fp_line
			(start 0.12065 -0.3048)
			(end 0.67945 -0.3048)
			(stroke
				(width 0.1)
				(type default)
			)
			(layer "F.Fab")
		)
		(fp_line
			(start 0.12065 -0.2794)
			(end 0.12065 -0.3048)
			(stroke
				(width 0.1)
				(type default)
			)
			(layer "F.Fab")
		)
		(fp_line
			(start 0.67945 -0.3048)
			(end 0.67945 0.3048)
			(stroke
				(width 0.1)
				(type default)
			)
			(layer "F.Fab")
		)
		(fp_line
			(start 0.67945 0.3048)
			(end 0.120396 0.3048)
			(stroke
				(width 0.1)
				(type default)
			)
			(layer "F.Fab")
		)
		(pad "1" smd circle
			(at -0.40005 0)
			(size 0 0)
			(layers "F.Cu" "F.Mask" "F.Paste")
			(net "GND")
		)
		(pad "2" smd circle
			(at 0.40005 0)
			(size 0 0)
			(layers "F.Cu" "F.Mask" "F.Paste")
			(net "PWRGD_P52V_HS_PG_R2")
		)
	)
	(footprint ""
		(layer "F.Cu")
		(at 142.93342 -39.4462 180)
		(property "Reference" "PR7039"
			(at 0 0 180)
			(layer "F.SilkS")
			(hide yes)
			(effects
				(font
					(size 1.27 1.27)
				)
			)
		)
		(property "Value" ""
			(at 0 0 180)
			(layer "F.Fab")
			(effects
				(font
					(size 1.27 1.27)
				)
			)
		)
		(duplicate_pad_numbers_are_jumpers no)
		(fp_line
			(start 0.7874 0.4064)
			(end -0.7874 0.4064)
			(stroke
				(width 0.1524)
				(type default)
			)
			(layer "F.SilkS")
		)
		(fp_line
			(start 0.7874 -0.4064)
			(end 0.7874 0.4064)
			(stroke
				(width 0.1524)
				(type default)
			)
			(layer "F.SilkS")
		)
		(fp_line
			(start -0.7874 0.4064)
			(end -0.7874 -0.4064)
			(stroke
				(width 0.1524)
				(type default)
			)
			(layer "F.SilkS")
		)
		(fp_line
			(start -0.7874 -0.4064)
			(end 0.7874 -0.4064)
			(stroke
				(width 0.1524)
				(type default)
			)
			(layer "F.SilkS")
		)
		(fp_line
			(start 0.67945 0.3048)
			(end 0.120396 0.3048)
			(stroke
				(width 0.1)
				(type default)
			)
			(layer "F.Fab")
		)
		(fp_line
			(start 0.67945 -0.3048)
			(end 0.67945 0.3048)
			(stroke
				(width 0.1)
				(type default)
			)
			(layer "F.Fab")
		)
		(fp_line
			(start 0.12065 -0.2794)
			(end 0.12065 -0.3048)
			(stroke
				(width 0.1)
				(type default)
			)
			(layer "F.Fab")
		)
		(fp_line
			(start 0.12065 -0.3048)
			(end 0.67945 -0.3048)
			(stroke
				(width 0.1)
				(type default)
			)
			(layer "F.Fab")
		)
		(fp_line
			(start 0.120396 0.3048)
			(end 0.120396 0.2794)
			(stroke
				(width 0.1)
				(type default)
			)
			(layer "F.Fab")
		)
		(fp_line
			(start 0.120396 0.2794)
			(end -0.12065 0.2794)
			(stroke
				(width 0.1)
				(type default)
			)
			(layer "F.Fab")
		)
		(fp_line
			(start -0.12065 0.3048)
			(end -0.67945 0.3048)
			(stroke
				(width 0.1)
				(type default)
			)
			(layer "F.Fab")
		)
		(fp_line
			(start -0.12065 0.2794)
			(end -0.12065 0.3048)
			(stroke
				(width 0.1)
				(type default)
			)
			(layer "F.Fab")
		)
		(fp_line
			(start -0.12065 -0.2794)
			(end 0.12065 -0.2794)
			(stroke
				(width 0.1)
				(type default)
			)
			(layer "F.Fab")
		)
		(fp_line
			(start -0.12065 -0.305054)
			(end -0.12065 -0.2794)
			(stroke
				(width 0.1)
				(type default)
			)
			(layer "F.Fab")
		)
		(fp_line
			(start -0.67945 0.3048)
			(end -0.67945 -0.305054)
			(stroke
				(width 0.1)
				(type default)
			)
			(layer "F.Fab")
		)
		(fp_line
			(start -0.67945 -0.305054)
			(end -0.12065 -0.305054)
			(stroke
				(width 0.1)
				(type default)
			)
			(layer "F.Fab")
		)
		(pad "1" smd circle
			(at -0.40005 0 180)
			(size 0 0)
			(layers "F.Cu" "F.Mask" "F.Paste")
			(net "P52V_HS2_4287_S2P")
		)
		(pad "2" smd circle
			(at 0.40005 0 180)
			(size 0 0)
			(layers "F.Cu" "F.Mask" "F.Paste")
			(net "P52V_HS2_4287_S2N")
		)
	)
	(footprint ""
		(layer "F.Cu")
		(at 450.445632 -89.48547 180)
		(property "Reference" "R392"
			(at 0 0 180)
			(layer "F.SilkS")
			(hide yes)
			(effects
				(font
					(size 1.27 1.27)
				)
			)
		)
		(property "Value" ""
			(at 0 0 180)
			(layer "F.Fab")
			(effects
				(font
					(size 1.27 1.27)
				)
			)
		)
		(duplicate_pad_numbers_are_jumpers no)
		(fp_line
			(start 0.7874 0.4064)
			(end -0.7874 0.4064)
			(stroke
				(width 0.1524)
				(type default)
			)
			(layer "F.SilkS")
		)
		(fp_line
			(start 0.7874 -0.4064)
			(end 0.7874 0.4064)
			(stroke
				(width 0.1524)
				(type default)
			)
			(layer "F.SilkS")
		)
		(fp_line
			(start -0.7874 0.4064)
			(end -0.7874 -0.4064)
			(stroke
				(width 0.1524)
				(type default)
			)
			(layer "F.SilkS")
		)
		(fp_line
			(start -0.7874 -0.4064)
			(end 0.7874 -0.4064)
			(stroke
				(width 0.1524)
				(type default)
			)
			(layer "F.SilkS")
		)
		(fp_line
			(start 0.67945 0.3048)
			(end 0.120396 0.3048)
			(stroke
				(width 0.1)
				(type default)
			)
			(layer "F.Fab")
		)
		(fp_line
			(start 0.67945 -0.3048)
			(end 0.67945 0.3048)
			(stroke
				(width 0.1)
				(type default)
			)
			(layer "F.Fab")
		)
		(fp_line
			(start 0.12065 -0.2794)
			(end 0.12065 -0.3048)
			(stroke
				(width 0.1)
				(type default)
			)
			(layer "F.Fab")
		)
		(fp_line
			(start 0.12065 -0.3048)
			(end 0.67945 -0.3048)
			(stroke
				(width 0.1)
				(type default)
			)
			(layer "F.Fab")
		)
		(fp_line
			(start 0.120396 0.3048)
			(end 0.120396 0.2794)
			(stroke
				(width 0.1)
				(type default)
			)
			(layer "F.Fab")
		)
		(fp_line
			(start 0.120396 0.2794)
			(end -0.12065 0.2794)
			(stroke
				(width 0.1)
				(type default)
			)
			(layer "F.Fab")
		)
		(fp_line
			(start -0.12065 0.3048)
			(end -0.67945 0.3048)
			(stroke
				(width 0.1)
				(type default)
			)
			(layer "F.Fab")
		)
		(fp_line
			(start -0.12065 0.2794)
			(end -0.12065 0.3048)
			(stroke
				(width 0.1)
				(type default)
			)
			(layer "F.Fab")
		)
		(fp_line
			(start -0.12065 -0.2794)
			(end 0.12065 -0.2794)
			(stroke
				(width 0.1)
				(type default)
			)
			(layer "F.Fab")
		)
		(fp_line
			(start -0.12065 -0.305054)
			(end -0.12065 -0.2794)
			(stroke
				(width 0.1)
				(type default)
			)
			(layer "F.Fab")
		)
		(fp_line
			(start -0.67945 0.3048)
			(end -0.67945 -0.305054)
			(stroke
				(width 0.1)
				(type default)
			)
			(layer "F.Fab")
		)
		(fp_line
			(start -0.67945 -0.305054)
			(end -0.12065 -0.305054)
			(stroke
				(width 0.1)
				(type default)
			)
			(layer "F.Fab")
		)
		(pad "1" smd rect
			(at -0.40005 0)
			(size 0.4572 0.508)
			(layers "F.Cu" "F.Mask" "F.Paste")
			(net "P12V_HPDB")
		)
		(pad "2" smd rect
			(at 0.40005 0)
			(size 0.4572 0.508)
			(layers "F.Cu" "F.Mask" "F.Paste")
			(net "P3V3_HPDB_EN")
		)
	)
	(footprint ""
		(layer "F.Cu")
		(at 33.85439 -34.671)
		(property "Reference" "R45"
			(at 0 0 0)
			(layer "F.SilkS")
			(hide yes)
			(effects
				(font
					(size 1.27 1.27)
				)
			)
		)
		(property "Value" ""
			(at 0 0 0)
			(layer "F.Fab")
			(effects
				(font
					(size 1.27 1.27)
				)
			)
		)
		(duplicate_pad_numbers_are_jumpers no)
		(fp_line
			(start -2.234946 -0.9271)
			(end 2.234946 -0.9271)
			(stroke
				(width 0.1524)
				(type default)
			)
			(layer "F.SilkS")
		)
		(fp_line
			(start -2.234946 0.9271)
			(end -2.234946 -0.9271)
			(stroke
				(width 0.1524)
				(type default)
			)
			(layer "F.SilkS")
		)
		(fp_line
			(start 2.234946 -0.9271)
			(end 2.234946 0.9271)
			(stroke
				(width 0.1524)
				(type default)
			)
			(layer "F.SilkS")
		)
		(fp_line
			(start 2.234946 0.9271)
			(end -2.234946 0.9271)
			(stroke
				(width 0.1524)
				(type default)
			)
			(layer "F.SilkS")
		)
		(fp_line
			(start -1.575054 -0.824992)
			(end -1.575054 0.824992)
			(stroke
				(width 0.1)
				(type default)
			)
			(layer "F.Fab")
		)
		(fp_line
			(start -1.575054 0.824992)
			(end 1.575054 0.824992)
			(stroke
				(width 0.1)
				(type default)
			)
			(layer "F.Fab")
		)
		(fp_line
			(start 1.575054 -0.824992)
			(end -1.575054 -0.824992)
			(stroke
				(width 0.1)
				(type default)
			)
			(layer "F.Fab")
		)
		(fp_line
			(start 1.575054 0.824992)
			(end 1.575054 -0.824992)
			(stroke
				(width 0.1)
				(type default)
			)
			(layer "F.Fab")
		)
		(pad "1" smd rect
			(at -1.599946 0)
			(size 1.016 1.6002)
			(layers "F.Cu" "F.Mask" "F.Paste")
			(net "LED_D2_R3")
		)
		(pad "2" smd rect
			(at 1.599946 0)
			(size 1.016 1.6002)
			(layers "F.Cu" "F.Mask" "F.Paste")
			(net "LED_D2_R4")
		)
	)
	(footprint ""
		(layer "F.Cu")
		(at 291.592 -63.881 180)
		(property "Reference" "PC4"
			(at 0 0 180)
			(layer "F.SilkS")
			(hide yes)
			(effects
				(font
					(size 1.27 1.27)
				)
			)
		)
		(property "Value" ""
			(at 0 0 180)
			(layer "F.Fab")
			(effects
				(font
					(size 1.27 1.27)
				)
			)
		)
		(duplicate_pad_numbers_are_jumpers no)
		(fp_line
			(start 0.7874 0.4064)
			(end -0.7874 0.4064)
			(stroke
				(width 0.1524)
				(type default)
			)
			(layer "F.SilkS")
		)
		(fp_line
			(start 0.7874 -0.4064)
			(end 0.7874 0.4064)
			(stroke
				(width 0.1524)
				(type default)
			)
			(layer "F.SilkS")
		)
		(fp_line
			(start -0.7874 0.4064)
			(end -0.7874 -0.4064)
			(stroke
				(width 0.1524)
				(type default)
			)
			(layer "F.SilkS")
		)
		(fp_line
			(start -0.7874 -0.4064)
			(end 0.7874 -0.4064)
			(stroke
				(width 0.1524)
				(type default)
			)
			(layer "F.SilkS")
		)
		(fp_line
			(start 0.67945 0.3048)
			(end 0.120396 0.3048)
			(stroke
				(width 0.1)
				(type default)
			)
			(layer "F.Fab")
		)
		(fp_line
			(start 0.67945 -0.3048)
			(end 0.67945 0.3048)
			(stroke
				(width 0.1)
				(type default)
			)
			(layer "F.Fab")
		)
		(fp_line
			(start 0.12065 -0.2794)
			(end 0.12065 -0.3048)
			(stroke
				(width 0.1)
				(type default)
			)
			(layer "F.Fab")
		)
		(fp_line
			(start 0.12065 -0.3048)
			(end 0.67945 -0.3048)
			(stroke
				(width 0.1)
				(type default)
			)
			(layer "F.Fab")
		)
		(fp_line
			(start 0.120396 0.3048)
			(end 0.120396 0.2794)
			(stroke
				(width 0.1)
				(type default)
			)
			(layer "F.Fab")
		)
		(fp_line
			(start 0.120396 0.2794)
			(end -0.12065 0.2794)
			(stroke
				(width 0.1)
				(type default)
			)
			(layer "F.Fab")
		)
		(fp_line
			(start -0.12065 0.3048)
			(end -0.67945 0.3048)
			(stroke
				(width 0.1)
				(type default)
			)
			(layer "F.Fab")
		)
		(fp_line
			(start -0.12065 0.2794)
			(end -0.12065 0.3048)
			(stroke
				(width 0.1)
				(type default)
			)
			(layer "F.Fab")
		)
		(fp_line
			(start -0.12065 -0.2794)
			(end 0.12065 -0.2794)
			(stroke
				(width 0.1)
				(type default)
			)
			(layer "F.Fab")
		)
		(fp_line
			(start -0.12065 -0.305054)
			(end -0.12065 -0.2794)
			(stroke
				(width 0.1)
				(type default)
			)
			(layer "F.Fab")
		)
		(fp_line
			(start -0.67945 0.3048)
			(end -0.67945 -0.305054)
			(stroke
				(width 0.1)
				(type default)
			)
			(layer "F.Fab")
		)
		(fp_line
			(start -0.67945 -0.305054)
			(end -0.12065 -0.305054)
			(stroke
				(width 0.1)
				(type default)
			)
			(layer "F.Fab")
		)
		(pad "1" smd circle
			(at -0.40005 0 180)
			(size 0 0)
			(layers "F.Cu" "F.Mask" "F.Paste")
			(net "P52V_HS1_INTVCC")
		)
		(pad "2" smd circle
			(at 0.40005 0 180)
			(size 0 0)
			(layers "F.Cu" "F.Mask" "F.Paste")
			(net "GND")
		)
	)
	(footprint ""
		(layer "F.Cu")
		(at 397.637 -119.38)
		(property "Reference" "PC31"
			(at -8.2296 -4.67233 0)
			(unlocked yes)
			(layer "F.SilkS")
			(effects
				(font
					(size 0.7874 0.5842)
					(thickness 0.1524)
				)
				(justify left)
			)
		)
		(property "Value" ""
			(at 0 0 0)
			(layer "F.Fab")
			(effects
				(font
					(size 1.27 1.27)
				)
			)
		)
		(duplicate_pad_numbers_are_jumpers no)
		(fp_line
			(start -9.253728 3.750056)
			(end 9.249918 3.750056)
			(stroke
				(width 0.1524)
				(type default)
			)
			(layer "F.SilkS")
		)
		(fp_line
			(start 0 3.750056)
			(end -9.253728 3.750056)
			(stroke
				(width 0.1524)
				(type default)
			)
			(layer "F.SilkS")
		)
		(fp_circle
			(center 0 3.750056)
			(end 9.249918 3.750056)
			(stroke
				(width 0.1524)
				(type default)
			)
			(fill no)
			(layer "F.SilkS")
		)
		(fp_poly
			(pts
				(arc
					(start 9.249918 3.750056)
					(mid 0 12.999974)
					(end -9.249918 3.750056)
				)
			)
			(stroke
				(width 0)
				(type default)
			)
			(fill yes)
			(layer "F.SilkS")
		)
		(fp_circle
			(center 0 3.750056)
			(end 9.249918 3.750056)
			(stroke
				(width 0.1)
				(type default)
			)
			(fill no)
			(layer "F.Fab")
		)
		(pad "1" thru_hole rect
			(at 0 0)
			(size 1.778 1.778)
			(drill 1.27)
			(layers "*.Cu" "*.Mask")
			(remove_unused_layers no)
			(net "P52V_HS1")
			(clearance 0)
			(padstack
				(mode front_inner_back)
				(layer "Inner"
					(shape circle)
					(size 1.778 1.778)
					(clearance 0)
				)
				(layer "B.Cu"
					(shape rect)
					(size 1.778 1.778)
					(clearance 0)
				)
			)
		)
		(pad "2" thru_hole circle
			(at 0 7.500112)
			(size 1.778 1.778)
			(drill 1.27)
			(layers "*.Cu" "*.Mask")
			(remove_unused_layers no)
			(net "GND")
			(clearance 0)
		)
	)
)
